(kicad_pcb
	(version 20241229)
	(generator "pcbnew")
	(generator_version "9.0")
	(general
		(thickness 1.6296)
		(legacy_teardrops no)
	)
	(paper "A3")
	(title_block
		(title "Thunderbolt to 10GbE adapter")
		(date "2026-04-21")
		(rev "1.1.0")
		(company "Antmicro Ltd")
		(comment 1 "www.antmicro.com")
		(comment 9 "footprints 238-242 of 703")
	)
	(layers
		(0 "F.Cu" signal)
		(4 "In1.Cu" signal)
		(6 "In2.Cu" signal)
		(8 "In3.Cu" signal)
		(10 "In4.Cu" signal)
		(12 "In5.Cu" signal)
		(14 "In6.Cu" signal)
		(2 "B.Cu" signal)
		(9 "F.Adhes" user "F.Adhesive")
		(11 "B.Adhes" user "B.Adhesive")
		(13 "F.Paste" user)
		(15 "B.Paste" user)
		(5 "F.SilkS" user "F.Silkscreen")
		(7 "B.SilkS" user "B.Silkscreen")
		(1 "F.Mask" user)
		(3 "B.Mask" user)
		(17 "Dwgs.User" user "User.Drawings")
		(19 "Cmts.User" user "User.Comments")
		(21 "Eco1.User" user "User.Eco1")
		(23 "Eco2.User" user "User.Eco2")
		(25 "Edge.Cuts" user)
		(27 "Margin" user)
		(31 "F.CrtYd" user "F.Courtyard")
		(29 "B.CrtYd" user "B.Courtyard")
		(35 "F.Fab" user)
		(33 "B.Fab" user)
	)
	(footprint "antmicro-footprints:C_0603_1608Metric"
		(layer "F.Cu")
		(at 122.15 104.7)
		(descr "Capacitor SMD 0603")
		(tags "capacitor 0603")
		(property "Reference" "C26"
			(at 2.35 -0.7 0)
			(layer "F.SilkS")
			(effects
				(font
					(size 0.7 0.7)
					(thickness 0.15)
				)
			)
		)
		(property "Value" "C_22u_0603"
			(at -1.42757 1.770288 0)
			(layer "F.Fab")
			(effects
				(font
					(size 0.7 0.7)
					(thickness 0.15)
				)
				(justify left bottom)
			)
		)
		(property "Datasheet" "https://www.murata.com/products/productdetail?partno=GRM188R60J226MEA0%23"
			(at 0 0 0)
			(layer "F.Fab")
			(hide yes)
			(effects
				(font
					(size 1.27 1.27)
					(thickness 0.15)
				)
			)
		)
		(property "Description" "SMD Multilayer Ceramic Capacitor, 22 µF, 6.3 V, 0603 [1608 Metric], ± 20%, X5R, GRM Series"
			(at 0 0 0)
			(layer "F.Fab")
			(hide yes)
			(effects
				(font
					(size 1.27 1.27)
					(thickness 0.15)
				)
			)
		)
		(property "MPN" "GRM188R60J226MEA0D"
			(at 0 0 0)
			(unlocked yes)
			(layer "F.Fab")
			(hide yes)
			(effects
				(font
					(size 1 1)
					(thickness 0.15)
				)
			)
		)
		(property "Manufacturer" "Murata"
			(at 0 0 0)
			(unlocked yes)
			(layer "F.Fab")
			(hide yes)
			(effects
				(font
					(size 1 1)
					(thickness 0.15)
				)
			)
		)
		(property "License" "Apache-2.0"
			(at 0 0 0)
			(unlocked yes)
			(layer "F.Fab")
			(hide yes)
			(effects
				(font
					(size 1 1)
					(thickness 0.15)
				)
			)
		)
		(property "Val" "22u"
			(at 0 0 0)
			(unlocked yes)
			(layer "F.Fab")
			(hide yes)
			(effects
				(font
					(size 1 1)
					(thickness 0.15)
				)
			)
		)
		(property "Voltage" ""
			(at 0 0 0)
			(unlocked yes)
			(layer "F.Fab")
			(hide yes)
			(effects
				(font
					(size 1 1)
					(thickness 0.15)
				)
			)
		)
		(property "Dielectric" ""
			(at 0 0 0)
			(unlocked yes)
			(layer "F.Fab")
			(hide yes)
			(effects
				(font
					(size 1 1)
					(thickness 0.15)
				)
			)
		)
		(property "Author" "Antmicro"
			(at 0 0 0)
			(unlocked yes)
			(layer "F.Fab")
			(hide yes)
			(effects
				(font
					(size 1 1)
					(thickness 0.15)
				)
			)
		)
		(sheetname "/PD and TB DC-DC/")
		(sheetfile "PD_and_TB_DC_DC.kicad_sch")
		(attr smd)
		(fp_line
			(start -0.15 -0.4)
			(end 0.15 -0.4)
			(stroke
				(width 0.15)
				(type solid)
			)
			(layer "F.SilkS")
		)
		(fp_line
			(start -0.15 0.4)
			(end 0.15 0.4)
			(stroke
				(width 0.15)
				(type solid)
			)
			(layer "F.SilkS")
		)
		(fp_rect
			(start -1.25 -0.65)
			(end 1.25 0.65)
			(stroke
				(width 0.05)
				(type solid)
			)
			(fill no)
			(layer "F.CrtYd")
		)
		(fp_rect
			(start -0.8 -0.4)
			(end 0.8 0.4)
			(stroke
				(width 0.15)
				(type solid)
			)
			(fill no)
			(layer "F.Fab")
		)
		(fp_text user "License: Apache-2.0"
			(at -1.682 5.895 0)
			(layer "F.Fab")
			(effects
				(font
					(size 0.7 0.7)
					(thickness 0.15)
				)
				(justify left bottom)
			)
		)
		(fp_text user "${REFERENCE}"
			(at -1.682 3.895 0)
			(layer "F.Fab")
			(effects
				(font
					(size 0.7 0.7)
					(thickness 0.15)
				)
				(justify left bottom)
			)
		)
		(fp_text user "Author: Antmicro"
			(at -1.682 4.894 0)
			(layer "F.Fab")
			(effects
				(font
					(size 0.7 0.7)
					(thickness 0.15)
				)
				(justify left bottom)
			)
		)
		(pad "1" smd roundrect
			(at -0.7 0)
			(size 0.8 1)
			(layers "F.Cu" "F.Mask" "F.Paste")
			(roundrect_rratio 0.2)
			(net 23 "GND")
			(pintype "passive")
		)
		(pad "2" smd roundrect
			(at 0.7 0)
			(size 0.8 1)
			(layers "F.Cu" "F.Mask" "F.Paste")
			(roundrect_rratio 0.2)
			(net 399 "Net-(D4-A)")
			(pintype "passive")
		)
	)
	(footprint "antmicro-footprints:C_0402_1005Metric"
		(layer "F.Cu")
		(at 134 93.75)
		(descr "Capacitor SMD 0402")
		(tags "capacitor SMD 0402")
		(property "Reference" "C119"
			(at 36.934999 -9.199999 0)
			(layer "F.SilkS")
			(effects
				(font
					(size 0.7 0.7)
					(thickness 0.15)
				)
			)
		)
		(property "Value" "C_1u_25V_0402"
			(at -1.022927 2.155213 0)
			(layer "F.Fab")
			(effects
				(font
					(size 0.7 0.7)
					(thickness 0.15)
				)
				(justify left bottom)
			)
		)
		(property "Datasheet" "https://www.murata.com/products/productdetail?partno=GRM155R61E105KE11%23"
			(at 0 0 0)
			(layer "F.Fab")
			(hide yes)
			(effects
				(font
					(size 1.27 1.27)
					(thickness 0.15)
				)
			)
		)
		(property "Description" "SMD Multilayer Ceramic Capacitor, 1 µF, 25 V, 0402 [1005 Metric], ± 10%, X5R, GRM Series"
			(at 0 0 0)
			(layer "F.Fab")
			(hide yes)
			(effects
				(font
					(size 1.27 1.27)
					(thickness 0.15)
				)
			)
		)
		(property "MPN" "GRM155R61E105KE11J"
			(at 0 0 0)
			(unlocked yes)
			(layer "F.Fab")
			(hide yes)
			(effects
				(font
					(size 1 1)
					(thickness 0.15)
				)
			)
		)
		(property "Manufacturer" "Murata"
			(at 0 0 0)
			(unlocked yes)
			(layer "F.Fab")
			(hide yes)
			(effects
				(font
					(size 1 1)
					(thickness 0.15)
				)
			)
		)
		(property "License" "Apache-2.0"
			(at 0 0 0)
			(unlocked yes)
			(layer "F.Fab")
			(hide yes)
			(effects
				(font
					(size 1 1)
					(thickness 0.15)
				)
			)
		)
		(property "Author" "Antmicro"
			(at 0 0 0)
			(unlocked yes)
			(layer "F.Fab")
			(hide yes)
			(effects
				(font
					(size 1 1)
					(thickness 0.15)
				)
			)
		)
		(property "Val" "1u"
			(at 0 0 0)
			(unlocked yes)
			(layer "F.Fab")
			(hide yes)
			(effects
				(font
					(size 1 1)
					(thickness 0.15)
				)
			)
		)
		(property "Voltage" "25V"
			(at 0 0 0)
			(unlocked yes)
			(layer "F.Fab")
			(hide yes)
			(effects
				(font
					(size 1 1)
					(thickness 0.15)
				)
			)
		)
		(property "Dielectric" "X5R"
			(at 0 0 0)
			(unlocked yes)
			(layer "F.Fab")
			(hide yes)
			(effects
				(font
					(size 1 1)
					(thickness 0.15)
				)
			)
		)
		(sheetname "/X710 DCDC converters/")
		(sheetfile "DCDC_converters_X710.kicad_sch")
		(attr smd)
		(fp_rect
			(start -0.925 -0.47)
			(end 0.925 0.47)
			(stroke
				(width 0.05)
				(type default)
			)
			(fill no)
			(layer "F.CrtYd")
		)
		(fp_line
			(start -0.494 -0.25)
			(end 0.504 -0.25)
			(stroke
				(width 0.15)
				(type solid)
			)
			(layer "F.Fab")
		)
		(fp_line
			(start -0.494 0.248)
			(end -0.494 -0.25)
			(stroke
				(width 0.15)
				(type solid)
			)
			(layer "F.Fab")
		)
		(fp_line
			(start 0.504 -0.25)
			(end 0.504 0.248)
			(stroke
				(width 0.15)
				(type solid)
			)
			(layer "F.Fab")
		)
		(fp_line
			(start 0.504 0.248)
			(end -0.494 0.248)
			(stroke
				(width 0.15)
				(type solid)
			)
			(layer "F.Fab")
		)
		(fp_text user "${REFERENCE}"
			(at -0.939 4.599 0)
			(layer "F.Fab")
			(effects
				(font
					(size 0.7 0.7)
					(thickness 0.15)
				)
				(justify left bottom)
			)
		)
		(fp_text user "Author: Antmicro"
			(at -0.939 3.399 0)
			(layer "F.Fab")
			(effects
				(font
					(size 0.7 0.7)
					(thickness 0.15)
				)
				(justify left bottom)
			)
		)
		(fp_text user "License: Apache-2.0"
			(at -0.939 5.799 0)
			(layer "F.Fab")
			(effects
				(font
					(size 0.7 0.7)
					(thickness 0.15)
				)
				(justify left bottom)
			)
		)
		(pad "1" smd roundrect
			(at -0.48 0)
			(size 0.59 0.64)
			(layers "F.Cu" "F.Mask" "F.Paste")
			(roundrect_rratio 0.25)
			(net 23 "GND")
			(pintype "passive")
		)
		(pad "2" smd roundrect
			(at 0.48 0)
			(size 0.59 0.64)
			(layers "F.Cu" "F.Mask" "F.Paste")
			(roundrect_rratio 0.25)
			(net 80 "/X710 DCDC converters/3V3_VCC")
			(pintype "passive")
		)
	)
	(footprint "antmicro-footprints:Vishay_PowerPAK_1212-8_Single"
		(layer "F.Cu")
		(at 142.243 57.693)
		(descr "PowerPAK 1212-8 Single")
		(tags "Vishay PowerPAK 1212-8 Single")
		(property "Reference" "Q7"
			(at 1.957 -1.893 0)
			(layer "F.SilkS")
			(effects
				(font
					(size 0.7 0.7)
					(thickness 0.15)
				)
				(justify left bottom)
			)
		)
		(property "Value" "SQS401EN-T1_BE3"
			(at 0 2.7 0)
			(layer "F.Fab")
			(effects
				(font
					(size 0.7 0.7)
					(thickness 0.15)
				)
				(justify left bottom)
			)
		)
		(property "Datasheet" "https://www.vishay.com/docs/65529/sqs401en.pdf"
			(at 0 0 0)
			(layer "F.Fab")
			(hide yes)
			(effects
				(font
					(size 1.27 1.27)
					(thickness 0.15)
				)
			)
		)
		(property "Description" "MOSFET, P Channel, 40 V, 16A, 0.047 ohm, PowerPAK 1212-8, Surface Mount"
			(at 0 0 0)
			(layer "F.Fab")
			(hide yes)
			(effects
				(font
					(size 1.27 1.27)
					(thickness 0.15)
				)
			)
		)
		(property "MPN" "SQS401EN-T1_BE3"
			(at 0 0 0)
			(unlocked yes)
			(layer "F.Fab")
			(hide yes)
			(effects
				(font
					(size 1 1)
					(thickness 0.15)
				)
			)
		)
		(property "Manufacturer" "Vishay"
			(at 0 0 0)
			(unlocked yes)
			(layer "F.Fab")
			(hide yes)
			(effects
				(font
					(size 1 1)
					(thickness 0.15)
				)
			)
		)
		(property "Author" "Antmicro"
			(at 0 0 0)
			(unlocked yes)
			(layer "F.Fab")
			(hide yes)
			(effects
				(font
					(size 1 1)
					(thickness 0.15)
				)
			)
		)
		(property "License" "Apache-2.0"
			(at 0 0 0)
			(unlocked yes)
			(layer "F.Fab")
			(hide yes)
			(effects
				(font
					(size 1 1)
					(thickness 0.15)
				)
			)
		)
		(sheetname "/Power input/")
		(sheetfile "power_input.kicad_sch")
		(attr smd)
		(fp_line
			(start -1.651 -1.651)
			(end -1.651 -1.317)
			(stroke
				(width 0.15)
				(type solid)
			)
			(layer "F.SilkS")
		)
		(fp_line
			(start -1.651 -1.651)
			(end 1.648 -1.651)
			(stroke
				(width 0.15)
				(type solid)
			)
			(layer "F.SilkS")
		)
		(fp_line
			(start -1.635 1.3)
			(end -1.635 1.634)
			(stroke
				(width 0.15)
				(type solid)
			)
			(layer "F.SilkS")
		)
		(fp_line
			(start -1.635 1.634)
			(end 1.634 1.634)
			(stroke
				(width 0.15)
				(type solid)
			)
			(layer "F.SilkS")
		)
		(fp_line
			(start 1.634 1.3)
			(end 1.634 1.634)
			(stroke
				(width 0.15)
				(type solid)
			)
			(layer "F.SilkS")
		)
		(fp_line
			(start 1.648 -1.651)
			(end 1.648 -1.317)
			(stroke
				(width 0.15)
				(type solid)
			)
			(layer "F.SilkS")
		)
		(fp_circle
			(center -1.9 -1.4)
			(end -1.85 -1.4)
			(stroke
				(width 0.15)
				(type solid)
			)
			(fill yes)
			(layer "F.SilkS")
		)
		(fp_rect
			(start -2 -1.8)
			(end 2 1.798)
			(stroke
				(width 0.05)
				(type solid)
			)
			(fill no)
			(layer "F.CrtYd")
		)
		(fp_line
			(start -1.6425 -1.4175)
			(end -1.4175 -1.6425)
			(stroke
				(width 0.15)
				(type solid)
			)
			(layer "F.Fab")
		)
		(fp_rect
			(start -1.651 -1.651)
			(end 1.648 1.648)
			(stroke
				(width 0.15)
				(type solid)
			)
			(fill no)
			(layer "F.Fab")
		)
		(fp_text user "License: Apache-2.0"
			(at -8 7.1 0)
			(layer "F.Fab")
			(effects
				(font
					(size 0.7 0.7)
					(thickness 0.15)
				)
				(justify left bottom)
			)
		)
		(fp_text user "Author: Antmicro"
			(at -8 5.9 0)
			(layer "F.Fab")
			(effects
				(font
					(size 0.7 0.7)
					(thickness 0.15)
				)
				(justify left bottom)
			)
		)
		(fp_text user "${REFERENCE}"
			(at -8 4.7 0)
			(layer "F.Fab")
			(effects
				(font
					(size 0.7 0.7)
					(thickness 0.15)
				)
				(justify left bottom)
			)
		)
		(pad "1" smd rect
			(at -1.436 -0.99)
			(size 0.99 0.405)
			(layers "F.Cu" "F.Mask" "F.Paste")
			(net 40 "+5V")
			(pinfunction "S")
			(pintype "passive")
		)
		(pad "2" smd rect
			(at -1.436 -0.332)
			(size 0.99 0.405)
			(layers "F.Cu" "F.Mask" "F.Paste")
			(net 40 "+5V")
			(pinfunction "S")
			(pintype "passive")
		)
		(pad "3" smd rect
			(at -1.436 0.33)
			(size 0.99 0.405)
			(layers "F.Cu" "F.Mask" "F.Paste")
			(net 40 "+5V")
			(pinfunction "S")
			(pintype "passive")
		)
		(pad "4" smd rect
			(at -1.436 0.988)
			(size 0.99 0.405)
			(layers "F.Cu" "F.Mask" "F.Paste")
			(net 432 "Net-(Q7-G)")
			(pinfunction "G")
			(pintype "passive")
		)
		(pad "5" smd custom
			(at 0.557 0)
			(size 1.725 2.235)
			(layers "F.Cu" "F.Mask" "F.Paste")
			(net 13 "/Power input/5V_JACK")
			(pinfunction "D")
			(pintype "passive")
			(zone_connect 2)
			(options
				(clearance outline)
				(anchor rect)
			)
			(primitives
				(gr_poly
					(pts
						(xy 0.8625 0.1275) (xy 0.8625 -0.1275) (xy 1.3725 -0.1275) (xy 1.3725 -0.5325) (xy 0.8625 -0.5325)
						(xy 0.8625 -0.7875) (xy 1.3725 -0.7875) (xy 1.3725 -1.195) (xy 0.6125 -1.195) (xy 0.6125 1.195)
						(xy 1.3725 1.195) (xy 1.3725 0.7875) (xy 0.8625 0.7875) (xy 0.8625 0.5325) (xy 1.3725 0.5325)
						(xy 1.3725 0.1275)
					)
					(width 0)
					(fill yes)
				)
			)
		)
	)
	(footprint "antmicro-footprints:R_0402_1005Metric"
		(layer "F.Cu")
		(at 164 75.4)
		(descr "Resistor SMD 0402")
		(tags "resistor SMD 0402")
		(property "Reference" "R139"
			(at -1 6.4 0)
			(layer "F.SilkS")
			(effects
				(font
					(size 0.7 0.7)
					(thickness 0.15)
				)
				(justify left bottom)
			)
		)
		(property "Value" "R_2k_0402"
			(at -1.011843 1.772047 0)
			(layer "F.Fab")
			(effects
				(font
					(size 0.7 0.7)
					(thickness 0.15)
				)
				(justify left bottom)
			)
		)
		(property "Datasheet" "https://www.bourns.com/docs/product-datasheets/cr.pdf"
			(at 0 0 0)
			(layer "F.Fab")
			(hide yes)
			(effects
				(font
					(size 1.27 1.27)
					(thickness 0.15)
				)
			)
		)
		(property "Description" "SMD Chip Resistor, 2 kohm, ± 1%, 62.5 mW, 0402 [1005 Metric], Thick Film, General Purpose"
			(at 0 0 0)
			(layer "F.Fab")
			(hide yes)
			(effects
				(font
					(size 1.27 1.27)
					(thickness 0.15)
				)
			)
		)
		(property "MPN" "CR0402-FX-2001GLF"
			(at 0 0 0)
			(unlocked yes)
			(layer "F.Fab")
			(hide yes)
			(effects
				(font
					(size 1 1)
					(thickness 0.15)
				)
			)
		)
		(property "Manufacturer" "Bourns"
			(at 0 0 0)
			(unlocked yes)
			(layer "F.Fab")
			(hide yes)
			(effects
				(font
					(size 1 1)
					(thickness 0.15)
				)
			)
		)
		(property "License" "Apache-2.0"
			(at 0 0 0)
			(unlocked yes)
			(layer "F.Fab")
			(hide yes)
			(effects
				(font
					(size 1 1)
					(thickness 0.15)
				)
			)
		)
		(property "Author" "Antmicro"
			(at 0 0 0)
			(unlocked yes)
			(layer "F.Fab")
			(hide yes)
			(effects
				(font
					(size 1 1)
					(thickness 0.15)
				)
			)
		)
		(property "Val" "2k"
			(at 0 0 0)
			(unlocked yes)
			(layer "F.Fab")
			(hide yes)
			(effects
				(font
					(size 1 1)
					(thickness 0.15)
				)
			)
		)
		(property "Tolerance" "1%"
			(at 0 0 0)
			(unlocked yes)
			(layer "F.Fab")
			(hide yes)
			(effects
				(font
					(size 1 1)
					(thickness 0.15)
				)
			)
		)
		(sheetname "/X710-AT2 Misc/")
		(sheetfile "x710-at2-mics.kicad_sch")
		(attr smd)
		(fp_rect
			(start -0.925 -0.47)
			(end 0.925 0.47)
			(stroke
				(width 0.05)
				(type default)
			)
			(fill no)
			(layer "F.CrtYd")
		)
		(fp_rect
			(start -0.5 -0.25)
			(end 0.5 0.25)
			(stroke
				(width 0.15)
				(type solid)
			)
			(fill no)
			(layer "F.Fab")
		)
		(fp_text user "Author: Antmicro"
			(at -0.95 4.169 0)
			(layer "F.Fab")
			(effects
				(font
					(size 0.7 0.7)
					(thickness 0.15)
				)
				(justify left bottom)
			)
		)
		(fp_text user "License: Apache-2.0"
			(at -0.95 5.169 0)
			(layer "F.Fab")
			(effects
				(font
					(size 0.7 0.7)
					(thickness 0.15)
				)
				(justify left bottom)
			)
		)
		(fp_text user "${REFERENCE}"
			(at -0.95 3.168 0)
			(layer "F.Fab")
			(effects
				(font
					(size 0.7 0.7)
					(thickness 0.15)
				)
				(justify left bottom)
			)
		)
		(pad "1" smd roundrect
			(at -0.48 0)
			(size 0.59 0.64)
			(layers "F.Cu" "F.Mask" "F.Paste")
			(roundrect_rratio 0.25)
			(net 146 "/X710-AT2 10GbE/~{PHY_RESET_3V3}")
			(pintype "passive")
		)
		(pad "2" smd roundrect
			(at 0.48 0)
			(size 0.59 0.64)
			(layers "F.Cu" "F.Mask" "F.Paste")
			(roundrect_rratio 0.25)
			(net 7 "+3V3")
			(pintype "passive")
		)
	)
	(footprint "antmicro-footprints:R_0402_1005Metric"
		(layer "F.Cu")
		(at 156.205 67.124999 90)
		(descr "Resistor SMD 0402")
		(tags "resistor SMD 0402")
		(property "Reference" "R152"
			(at 12.324999 20.295 90)
			(layer "F.SilkS")
			(effects
				(font
					(size 0.7 0.7)
					(thickness 0.15)
				)
			)
		)
		(property "Value" "R_100k_0402"
			(at -1.011843 1.772047 90)
			(layer "F.Fab")
			(effects
				(font
					(size 0.7 0.7)
					(thickness 0.15)
				)
				(justify left bottom)
			)
		)
		(property "Datasheet" "https://www.bourns.com/docs/product-datasheets/cr.pdf"
			(at 0 0 90)
			(layer "F.Fab")
			(hide yes)
			(effects
				(font
					(size 1.27 1.27)
					(thickness 0.15)
				)
			)
		)
		(property "Description" "SMD Chip Resistor, 100 kohm, ± 1%, 62.5 mW, 0402 [1005 Metric], Thick Film, General Purpose"
			(at 0 0 90)
			(layer "F.Fab")
			(hide yes)
			(effects
				(font
					(size 1.27 1.27)
					(thickness 0.15)
				)
			)
		)
		(property "MPN" "CR0402-FX-1003GLF"
			(at 0 0 90)
			(unlocked yes)
			(layer "F.Fab")
			(hide yes)
			(effects
				(font
					(size 1 1)
					(thickness 0.15)
				)
			)
		)
		(property "Manufacturer" "Bourns"
			(at 0 0 90)
			(unlocked yes)
			(layer "F.Fab")
			(hide yes)
			(effects
				(font
					(size 1 1)
					(thickness 0.15)
				)
			)
		)
		(property "License" "Apache-2.0"
			(at 0 0 90)
			(unlocked yes)
			(layer "F.Fab")
			(hide yes)
			(effects
				(font
					(size 1 1)
					(thickness 0.15)
				)
			)
		)
		(property "Author" "Antmicro"
			(at 0 0 90)
			(unlocked yes)
			(layer "F.Fab")
			(hide yes)
			(effects
				(font
					(size 1 1)
					(thickness 0.15)
				)
			)
		)
		(property "Val" "100k"
			(at 0 0 90)
			(unlocked yes)
			(layer "F.Fab")
			(hide yes)
			(effects
				(font
					(size 1 1)
					(thickness 0.15)
				)
			)
		)
		(property "Tolerance" "1%"
			(at 0 0 90)
			(unlocked yes)
			(layer "F.Fab")
			(hide yes)
			(effects
				(font
					(size 1 1)
					(thickness 0.15)
				)
			)
		)
		(sheetname "/X710-AT2 Misc/")
		(sheetfile "x710-at2-mics.kicad_sch")
		(attr smd)
		(fp_rect
			(start -0.925 -0.47)
			(end 0.925 0.47)
			(stroke
				(width 0.05)
				(type default)
			)
			(fill no)
			(layer "F.CrtYd")
		)
		(fp_rect
			(start -0.5 -0.25)
			(end 0.5 0.25)
			(stroke
				(width 0.15)
				(type solid)
			)
			(fill no)
			(layer "F.Fab")
		)
		(fp_text user "${REFERENCE}"
			(at -0.95 3.168 90)
			(layer "F.Fab")
			(effects
				(font
					(size 0.7 0.7)
					(thickness 0.15)
				)
				(justify left bottom)
			)
		)
		(fp_text user "Author: Antmicro"
			(at -0.95 4.169 90)
			(layer "F.Fab")
			(effects
				(font
					(size 0.7 0.7)
					(thickness 0.15)
				)
				(justify left bottom)
			)
		)
		(fp_text user "License: Apache-2.0"
			(at -0.95 5.169 90)
			(layer "F.Fab")
			(effects
				(font
					(size 0.7 0.7)
					(thickness 0.15)
				)
				(justify left bottom)
			)
		)
		(pad "1" smd roundrect
			(at -0.48 0 90)
			(size 0.59 0.64)
			(layers "F.Cu" "F.Mask" "F.Paste")
			(roundrect_rratio 0.25)
			(net 23 "GND")
			(pintype "passive")
		)
		(pad "2" smd roundrect
			(at 0.48 0 90)
			(size 0.59 0.64)
			(layers "F.Cu" "F.Mask" "F.Paste")
			(roundrect_rratio 0.25)
			(net 142 "/X710-AT2 Misc/NCSI.CRS_DV")
			(pintype "passive")
		)
	)
)
